#ISCELL
  mstr_misc prelim *
  *
#ISCELL
  mstr_symbols design_note *
  *
#ISCELL
  mstr_symbols intel_corp_bpage *
  *
#ISCELL
  mstr_standard offpage *
  page23_i1
#ISCELL
  mstr_standard tap *
  page23_i10
#ISCELL
  mstr_standard tap *
  page23_i100
#ISCELL
  mstr_standard tap *
  page23_i101
#ISCELL
  mstr_standard tap *
  page23_i102
#ISCELL
  mstr_standard tap *
  page23_i103
#ISCELL
  mstr_standard tap *
  page23_i104
#ISCELL
  mstr_standard tap *
  page23_i105
#ISCELL
  mstr_standard tap *
  page23_i106
#ISCELL
  mstr_standard tap *
  page23_i107
#ISCELL
  mstr_standard tap *
  page23_i108
#ISCELL
  mstr_standard tap *
  page23_i109
#ISCELL
  mstr_standard tap *
  page23_i11
#ISCELL
  mstr_standard tap *
  page23_i110
#ISCELL
  mstr_standard tap *
  page23_i111
#ISCELL
  mstr_standard tap *
  page23_i112
#ISCELL
  mstr_standard tap *
  page23_i113
#ISCELL
  mstr_standard tap *
  page23_i114
#ISCELL
  mstr_standard tap *
  page23_i115
#ISCELL
  mstr_standard tap *
  page23_i116
#ISCELL
  mstr_standard tap *
  page23_i117
#ISCELL
  mstr_standard tap *
  page23_i118
#ISCELL
  mstr_standard tap *
  page23_i119
#ISCELL
  mstr_standard tap *
  page23_i12
#ISCELL
  mstr_standard tap *
  page23_i120
#ISCELL
  mstr_standard tap *
  page23_i121
#ISCELL
  mstr_standard tap *
  page23_i122
#ISCELL
  mstr_standard tap *
  page23_i123
#ISCELL
  mstr_standard tap *
  page23_i124
#ISCELL
  mstr_standard tap *
  page23_i125
#ISCELL
  mstr_standard tap *
  page23_i126
#ISCELL
  mstr_standard tap *
  page23_i127
#ISCELL
  mstr_standard tap *
  page23_i128
#ISCELL
  mstr_standard tap *
  page23_i129
#ISCELL
  mstr_standard tap *
  page23_i13
#ISCELL
  mstr_standard tap *
  page23_i130
#ISCELL
  mstr_standard tap *
  page23_i131
#ISCELL
  mstr_standard tap *
  page23_i132
#ISCELL
  mstr_standard tap *
  page23_i133
#ISCELL
  mstr_standard tap *
  page23_i134
#ISCELL
  mstr_standard tap *
  page23_i135
#ISCELL
  mstr_standard tap *
  page23_i136
#ISCELL
  mstr_standard tap *
  page23_i137
#ISCELL
  mstr_standard tap *
  page23_i138
#ISCELL
  mstr_standard tap *
  page23_i139
#ISCELL
  mstr_standard tap *
  page23_i14
#ISCELL
  mstr_standard tap *
  page23_i140
#ISCELL
  mstr_standard tap *
  page23_i141
#ISCELL
  mstr_standard tap *
  page23_i142
#ISCELL
  mstr_standard tap *
  page23_i143
#ISCELL
  mstr_standard tap *
  page23_i144
#ISCELL
  mstr_standard tap *
  page23_i145
#ISCELL
  mstr_standard tap *
  page23_i146
#ISCELL
  mstr_standard offpage *
  page23_i147
#ISCELL
  mstr_standard offpage *
  page23_i148
#ISCELL
  mstr_standard offpage *
  page23_i149
#ISCELL
  mstr_standard tap *
  page23_i15
#ISCELL
  mstr_standard offpage *
  page23_i150
#ISCELL
  mstr_standard offpage *
  page23_i151
#ISCELL
  mstr_standard offpage *
  page23_i152
#ISCELL
  mstr_standard offpage *
  page23_i153
#ISCELL
  mstr_standard offpage *
  page23_i154
#ISCELL
  mstr_standard offpage *
  page23_i155
#ISCELL
  mstr_standard offpage *
  page23_i156
#ISCELL
  mstr_standard tap *
  page23_i157
#ISCELL
  mstr_standard tap *
  page23_i158
#ISCELL
  mstr_standard tap *
  page23_i159
#ISCELL
  mstr_standard tap *
  page23_i16
#ISCELL
  mstr_standard tap *
  page23_i160
#ISCELL
  mstr_standard tap *
  page23_i161
#ISCELL
  mstr_standard tap *
  page23_i162
#ISCELL
  mstr_standard tap *
  page23_i163
#ISCELL
  mstr_standard tap *
  page23_i164
#ISCELL
  mstr_standard tap *
  page23_i165
#ISCELL
  mstr_standard tap *
  page23_i166
#ISCELL
  mstr_standard tap *
  page23_i167
#ISCELL
  mstr_standard tap *
  page23_i168
#ISCELL
  mstr_standard tap *
  page23_i169
#ISCELL
  mstr_standard tap *
  page23_i17
#ISCELL
  mstr_standard tap *
  page23_i170
#ISCELL
  mstr_standard offpage *
  page23_i171
#CELL
  chpset_lib skx_ext_b *
  page23_i172
#ISCELL
  mstr_standard tap *
  page23_i18
#ISCELL
  mstr_standard tap *
  page23_i19
#ISCELL
  mstr_standard offpage *
  page23_i2
#ISCELL
  mstr_standard tap *
  page23_i20
#ISCELL
  mstr_standard tap *
  page23_i21
#ISCELL
  mstr_standard tap *
  page23_i22
#ISCELL
  mstr_standard tap *
  page23_i23
#ISCELL
  mstr_standard tap *
  page23_i24
#ISCELL
  mstr_standard tap *
  page23_i25
#ISCELL
  mstr_standard tap *
  page23_i26
#ISCELL
  mstr_standard tap *
  page23_i27
#ISCELL
  mstr_standard tap *
  page23_i28
#ISCELL
  mstr_standard tap *
  page23_i29
#ISCELL
  mstr_standard offpage *
  page23_i3
#ISCELL
  mstr_standard tap *
  page23_i31
#ISCELL
  mstr_standard tap *
  page23_i32
#ISCELL
  mstr_standard tap *
  page23_i33
#ISCELL
  mstr_standard tap *
  page23_i34
#ISCELL
  mstr_standard tap *
  page23_i35
#ISCELL
  mstr_standard tap *
  page23_i36
#ISCELL
  mstr_standard tap *
  page23_i37
#ISCELL
  mstr_standard tap *
  page23_i38
#ISCELL
  mstr_standard tap *
  page23_i39
#ISCELL
  mstr_standard offpage *
  page23_i4
#ISCELL
  mstr_standard tap *
  page23_i40
#ISCELL
  mstr_standard tap *
  page23_i41
#ISCELL
  mstr_standard tap *
  page23_i42
#ISCELL
  mstr_standard tap *
  page23_i43
#ISCELL
  mstr_standard tap *
  page23_i44
#ISCELL
  mstr_standard tap *
  page23_i45
#ISCELL
  mstr_standard tap *
  page23_i46
#ISCELL
  mstr_standard tap *
  page23_i47
#ISCELL
  mstr_standard tap *
  page23_i48
#ISCELL
  mstr_standard tap *
  page23_i49
#ISCELL
  mstr_standard tap *
  page23_i5
#ISCELL
  mstr_standard tap *
  page23_i50
#ISCELL
  mstr_standard tap *
  page23_i51
#ISCELL
  mstr_standard tap *
  page23_i52
#ISCELL
  mstr_standard tap *
  page23_i53
#ISCELL
  mstr_standard tap *
  page23_i54
#ISCELL
  mstr_standard tap *
  page23_i55
#ISCELL
  mstr_standard tap *
  page23_i56
#ISCELL
  mstr_standard tap *
  page23_i57
#ISCELL
  mstr_standard tap *
  page23_i58
#ISCELL
  mstr_standard tap *
  page23_i59
#ISCELL
  mstr_standard tap *
  page23_i6
#ISCELL
  mstr_standard tap *
  page23_i60
#ISCELL
  mstr_standard tap *
  page23_i61
#ISCELL
  mstr_standard tap *
  page23_i62
#ISCELL
  mstr_standard tap *
  page23_i63
#ISCELL
  mstr_standard tap *
  page23_i64
#ISCELL
  mstr_standard tap *
  page23_i65
#ISCELL
  mstr_standard tap *
  page23_i66
#ISCELL
  mstr_standard tap *
  page23_i67
#ISCELL
  mstr_standard tap *
  page23_i68
#ISCELL
  mstr_standard tap *
  page23_i69
#ISCELL
  mstr_standard tap *
  page23_i7
#ISCELL
  mstr_standard tap *
  page23_i70
#ISCELL
  mstr_standard tap *
  page23_i71
#ISCELL
  mstr_standard offpage *
  page23_i72
#ISCELL
  mstr_standard tap *
  page23_i73
#ISCELL
  mstr_standard tap *
  page23_i74
#ISCELL
  mstr_standard tap *
  page23_i75
#ISCELL
  mstr_standard tap *
  page23_i76
#ISCELL
  mstr_standard tap *
  page23_i77
#ISCELL
  mstr_standard tap *
  page23_i78
#ISCELL
  mstr_standard tap *
  page23_i79
#ISCELL
  mstr_standard tap *
  page23_i8
#ISCELL
  mstr_standard tap *
  page23_i80
#ISCELL
  mstr_standard tap *
  page23_i81
#ISCELL
  mstr_standard tap *
  page23_i82
#ISCELL
  mstr_standard tap *
  page23_i83
#ISCELL
  mstr_standard tap *
  page23_i84
#ISCELL
  mstr_standard tap *
  page23_i85
#ISCELL
  mstr_standard tap *
  page23_i86
#ISCELL
  mstr_standard tap *
  page23_i87
#ISCELL
  mstr_standard tap *
  page23_i88
#ISCELL
  mstr_standard tap *
  page23_i89
#ISCELL
  mstr_standard tap *
  page23_i9
#ISCELL
  mstr_standard tap *
  page23_i90
#ISCELL
  mstr_standard tap *
  page23_i91
#ISCELL
  mstr_standard tap *
  page23_i92
#ISCELL
  mstr_standard tap *
  page23_i93
#ISCELL
  mstr_standard tap *
  page23_i94
#ISCELL
  mstr_standard tap *
  page23_i95
#ISCELL
  mstr_standard tap *
  page23_i96
#ISCELL
  mstr_standard tap *
  page23_i97
#ISCELL
  mstr_standard tap *
  page23_i98
#ISCELL
  mstr_standard tap *
  page23_i99
